(kicad_pcb
	(version 20260206)
	(generator "pcbnew")
	(generator_version "10.0")
	(general
		(thickness 1.6)
		(legacy_teardrops no)
	)
	(paper "A4")
	(title_block
		(title "04192023_DAF0TMB3IC0_F0TG_MB_C_brd_V02_OCP.brd")
		(comment 1 "Grand Teton / footprints 2731-2737 of 8354")
	)
	(layers
		(0 "F.Cu" signal "TOP")
		(4 "In1.Cu" signal "GND")
		(6 "In2.Cu" signal "IN1")
		(8 "In3.Cu" signal "GND1")
		(10 "In4.Cu" signal "IN2")
		(12 "In5.Cu" signal "GND2")
		(14 "In6.Cu" signal "IN3")
		(16 "In7.Cu" signal "GND3")
		(18 "In8.Cu" signal "VCC")
		(20 "In9.Cu" signal "VCC1")
		(22 "In10.Cu" signal "GND4")
		(24 "In11.Cu" signal "IN4")
		(26 "In12.Cu" signal "GND5")
		(28 "In13.Cu" signal "IN5")
		(30 "In14.Cu" signal "GND6")
		(32 "In15.Cu" signal "IN6")
		(34 "In16.Cu" signal "GND7")
		(2 "B.Cu" signal "BOTTOM")
		(9 "F.Adhes" user "F.Adhesive")
		(11 "B.Adhes" user "B.Adhesive")
		(13 "F.Paste" user "Package Geometry/Pastemask Top")
		(15 "B.Paste" user "Package Geometry/Pastemask Bottom")
		(5 "F.SilkS" user "Ref Des/Silkscreen Top")
		(7 "B.SilkS" user "Ref Des/Silkscreen Bottom")
		(1 "F.Mask" user "Board Geometry/Soldermask Top")
		(3 "B.Mask" user "Board Geometry/Soldermask Bottom")
		(17 "Dwgs.User" user "User.Drawings")
		(19 "Cmts.User" user "User.Comments")
		(21 "Eco1.User" user "User.Eco1")
		(23 "Eco2.User" user "User.Eco2")
		(25 "Edge.Cuts" user "Board Geometry/Outline")
		(27 "Margin" user)
		(31 "F.CrtYd" user "Package Geometry/Place Bound Top")
		(29 "B.CrtYd" user "Package Geometry/Place Bound Bottom")
		(35 "F.Fab" user "Ref Des/Assembly Top")
		(33 "B.Fab" user "Ref Des/Assembly Bottom")
	)
	(footprint ""
		(layer "F.Cu")
		(at 367.931446 -30.135322 90)
		(property "Reference" "R823"
			(at 0 0 90)
			(layer "F.SilkS")
			(hide yes)
			(effects
				(font
					(size 1.27 1.27)
				)
			)
		)
		(property "Value" ""
			(at 0 0 90)
			(layer "F.Fab")
			(effects
				(font
					(size 1.27 1.27)
				)
			)
		)
		(duplicate_pad_numbers_are_jumpers no)
		(fp_line
			(start 0.7874 -0.4064)
			(end 0.7874 0.4064)
			(stroke
				(width 0.1524)
				(type default)
			)
			(layer "F.SilkS")
		)
		(fp_line
			(start -0.7874 -0.4064)
			(end 0.7874 -0.4064)
			(stroke
				(width 0.1524)
				(type default)
			)
			(layer "F.SilkS")
		)
		(fp_line
			(start 0.7874 0.4064)
			(end -0.7874 0.4064)
			(stroke
				(width 0.1524)
				(type default)
			)
			(layer "F.SilkS")
		)
		(fp_line
			(start -0.7874 0.4064)
			(end -0.7874 -0.4064)
			(stroke
				(width 0.1524)
				(type default)
			)
			(layer "F.SilkS")
		)
		(fp_line
			(start -0.12065 -0.305054)
			(end -0.12065 -0.2794)
			(stroke
				(width 0.1)
				(type default)
			)
			(layer "F.Fab")
		)
		(fp_line
			(start -0.67945 -0.305054)
			(end -0.12065 -0.305054)
			(stroke
				(width 0.1)
				(type default)
			)
			(layer "F.Fab")
		)
		(fp_line
			(start 0.67945 -0.3048)
			(end 0.67945 0.3048)
			(stroke
				(width 0.1)
				(type default)
			)
			(layer "F.Fab")
		)
		(fp_line
			(start 0.12065 -0.3048)
			(end 0.67945 -0.3048)
			(stroke
				(width 0.1)
				(type default)
			)
			(layer "F.Fab")
		)
		(fp_line
			(start 0.12065 -0.2794)
			(end 0.12065 -0.3048)
			(stroke
				(width 0.1)
				(type default)
			)
			(layer "F.Fab")
		)
		(fp_line
			(start -0.12065 -0.2794)
			(end 0.12065 -0.2794)
			(stroke
				(width 0.1)
				(type default)
			)
			(layer "F.Fab")
		)
		(fp_line
			(start 0.120396 0.2794)
			(end -0.12065 0.2794)
			(stroke
				(width 0.1)
				(type default)
			)
			(layer "F.Fab")
		)
		(fp_line
			(start -0.12065 0.2794)
			(end -0.12065 0.3048)
			(stroke
				(width 0.1)
				(type default)
			)
			(layer "F.Fab")
		)
		(fp_line
			(start 0.67945 0.3048)
			(end 0.120396 0.3048)
			(stroke
				(width 0.1)
				(type default)
			)
			(layer "F.Fab")
		)
		(fp_line
			(start 0.120396 0.3048)
			(end 0.120396 0.2794)
			(stroke
				(width 0.1)
				(type default)
			)
			(layer "F.Fab")
		)
		(fp_line
			(start -0.12065 0.3048)
			(end -0.67945 0.3048)
			(stroke
				(width 0.1)
				(type default)
			)
			(layer "F.Fab")
		)
		(fp_line
			(start -0.67945 0.3048)
			(end -0.67945 -0.305054)
			(stroke
				(width 0.1)
				(type default)
			)
			(layer "F.Fab")
		)
		(pad "1" smd circle
			(at -0.40005 0 90)
			(size 0 0)
			(layers "F.Cu" "F.Mask" "F.Paste")
			(net "P3V3_AUX")
		)
		(pad "2" smd circle
			(at 0.40005 0 90)
			(size 0 0)
			(layers "F.Cu" "F.Mask" "F.Paste")
			(net "UART_CPU0_SCM_LVC3_UART1_R_RX")
		)
	)
	(footprint ""
		(layer "F.Cu")
		(at 224.898712 -67.921378)
		(property "Reference" "R3973"
			(at 0 0 0)
			(layer "F.SilkS")
			(hide yes)
			(effects
				(font
					(size 1.27 1.27)
				)
			)
		)
		(property "Value" ""
			(at 0 0 0)
			(layer "F.Fab")
			(effects
				(font
					(size 1.27 1.27)
				)
			)
		)
		(duplicate_pad_numbers_are_jumpers no)
		(fp_line
			(start -0.7874 -0.4064)
			(end 0.7874 -0.4064)
			(stroke
				(width 0.1524)
				(type default)
			)
			(layer "F.SilkS")
		)
		(fp_line
			(start -0.7874 0.4064)
			(end -0.7874 -0.4064)
			(stroke
				(width 0.1524)
				(type default)
			)
			(layer "F.SilkS")
		)
		(fp_line
			(start 0.7874 -0.4064)
			(end 0.7874 0.4064)
			(stroke
				(width 0.1524)
				(type default)
			)
			(layer "F.SilkS")
		)
		(fp_line
			(start 0.7874 0.4064)
			(end -0.7874 0.4064)
			(stroke
				(width 0.1524)
				(type default)
			)
			(layer "F.SilkS")
		)
		(fp_line
			(start -0.67945 -0.305054)
			(end -0.12065 -0.305054)
			(stroke
				(width 0.1)
				(type default)
			)
			(layer "F.Fab")
		)
		(fp_line
			(start -0.67945 0.3048)
			(end -0.67945 -0.305054)
			(stroke
				(width 0.1)
				(type default)
			)
			(layer "F.Fab")
		)
		(fp_line
			(start -0.12065 -0.305054)
			(end -0.12065 -0.2794)
			(stroke
				(width 0.1)
				(type default)
			)
			(layer "F.Fab")
		)
		(fp_line
			(start -0.12065 -0.2794)
			(end 0.12065 -0.2794)
			(stroke
				(width 0.1)
				(type default)
			)
			(layer "F.Fab")
		)
		(fp_line
			(start -0.12065 0.2794)
			(end -0.12065 0.3048)
			(stroke
				(width 0.1)
				(type default)
			)
			(layer "F.Fab")
		)
		(fp_line
			(start -0.12065 0.3048)
			(end -0.67945 0.3048)
			(stroke
				(width 0.1)
				(type default)
			)
			(layer "F.Fab")
		)
		(fp_line
			(start 0.120396 0.2794)
			(end -0.12065 0.2794)
			(stroke
				(width 0.1)
				(type default)
			)
			(layer "F.Fab")
		)
		(fp_line
			(start 0.120396 0.3048)
			(end 0.120396 0.2794)
			(stroke
				(width 0.1)
				(type default)
			)
			(layer "F.Fab")
		)
		(fp_line
			(start 0.12065 -0.3048)
			(end 0.67945 -0.3048)
			(stroke
				(width 0.1)
				(type default)
			)
			(layer "F.Fab")
		)
		(fp_line
			(start 0.12065 -0.2794)
			(end 0.12065 -0.3048)
			(stroke
				(width 0.1)
				(type default)
			)
			(layer "F.Fab")
		)
		(fp_line
			(start 0.67945 -0.3048)
			(end 0.67945 0.3048)
			(stroke
				(width 0.1)
				(type default)
			)
			(layer "F.Fab")
		)
		(fp_line
			(start 0.67945 0.3048)
			(end 0.120396 0.3048)
			(stroke
				(width 0.1)
				(type default)
			)
			(layer "F.Fab")
		)
		(pad "1" smd circle
			(at -0.40005 0)
			(size 0 0)
			(layers "F.Cu" "F.Mask" "F.Paste")
			(net "P3V3_E1S_PWRGD_0")
		)
		(pad "2" smd circle
			(at 0.40005 0)
			(size 0 0)
			(layers "F.Cu" "F.Mask" "F.Paste")
			(net "P3V3_E1S_PWRGD_0_R")
		)
	)
	(footprint ""
		(layer "F.Cu")
		(at 114.197638 -395.221206 -90)
		(property "Reference" "R924"
			(at 0 0 270)
			(layer "F.SilkS")
			(hide yes)
			(effects
				(font
					(size 1.27 1.27)
				)
			)
		)
		(property "Value" ""
			(at 0 0 270)
			(layer "F.Fab")
			(effects
				(font
					(size 1.27 1.27)
				)
			)
		)
		(duplicate_pad_numbers_are_jumpers no)
		(fp_line
			(start -0.32512 0.175006)
			(end -0.32512 -0.175006)
			(stroke
				(width 0.1)
				(type default)
			)
			(layer "F.Fab")
		)
		(fp_line
			(start 0.32512 0.175006)
			(end -0.32512 0.175006)
			(stroke
				(width 0.1)
				(type default)
			)
			(layer "F.Fab")
		)
		(fp_line
			(start -0.32512 -0.175006)
			(end 0.32512 -0.175006)
			(stroke
				(width 0.1)
				(type default)
			)
			(layer "F.Fab")
		)
		(fp_line
			(start 0.32512 -0.175006)
			(end 0.32512 0.175006)
			(stroke
				(width 0.1)
				(type default)
			)
			(layer "F.Fab")
		)
		(pad "1" smd rect
			(at -0.2667 0 270)
			(size 0.3048 0.381)
			(layers "F.Cu" "F.Mask" "F.Paste")
			(net "JTAG_TEST_MODE_RT_CPU1_P3")
		)
		(pad "2" smd rect
			(at 0.2667 0 90)
			(size 0.3048 0.381)
			(layers "F.Cu" "F.Mask" "F.Paste")
			(net "GND")
		)
	)
	(footprint ""
		(layer "F.Cu")
		(at 450.857366 -180.106066 180)
		(property "Reference" "R1838"
			(at -4.945634 -3.856736 0)
			(unlocked yes)
			(layer "F.SilkS")
			(effects
				(font
					(size 0.7874 0.5842)
					(thickness 0.1524)
				)
				(justify left)
			)
		)
		(property "Value" ""
			(at 0 0 180)
			(layer "F.Fab")
			(effects
				(font
					(size 1.27 1.27)
				)
			)
		)
		(duplicate_pad_numbers_are_jumpers no)
		(fp_line
			(start 4.0386 1.7526)
			(end -4.0386 1.7526)
			(stroke
				(width 0.1524)
				(type default)
			)
			(layer "F.SilkS")
		)
		(fp_line
			(start 4.0386 -1.7526)
			(end 4.0386 1.7526)
			(stroke
				(width 0.1524)
				(type default)
			)
			(layer "F.SilkS")
		)
		(fp_line
			(start -4.0386 1.7526)
			(end -4.0386 -1.7526)
			(stroke
				(width 0.1524)
				(type default)
			)
			(layer "F.SilkS")
		)
		(fp_line
			(start -4.0386 -1.7526)
			(end 4.0386 -1.7526)
			(stroke
				(width 0.1524)
				(type default)
			)
			(layer "F.SilkS")
		)
		(fp_line
			(start 4.0386 1.7526)
			(end -4.0386 1.7526)
			(stroke
				(width 0.1)
				(type default)
			)
			(layer "F.Fab")
		)
		(fp_line
			(start 4.0386 -1.7526)
			(end 4.0386 1.7526)
			(stroke
				(width 0.1)
				(type default)
			)
			(layer "F.Fab")
		)
		(fp_line
			(start -4.0386 1.7526)
			(end -4.0386 -1.7526)
			(stroke
				(width 0.1)
				(type default)
			)
			(layer "F.Fab")
		)
		(fp_line
			(start -4.0386 -1.7526)
			(end 4.0386 -1.7526)
			(stroke
				(width 0.1)
				(type default)
			)
			(layer "F.Fab")
		)
		(pad "1" smd circle
			(at -3.700018 0 90)
			(size 0 0)
			(layers "F.Cu" "F.Mask" "F.Paste")
			(net "P12V_AUX")
		)
		(pad "2" smd circle
			(at 3.700018 0 270)
			(size 0 0)
			(layers "F.Cu" "F.Mask" "F.Paste")
			(net "P12V_MEM_CPU0")
		)
		(pad "3" smd rect
			(at -2.70002 0 270)
			(size 0.4064 1.1176)
			(layers "F.Cu" "F.Mask" "F.Paste")
			(net "TP_P12V_AUX_CPU0_DIMM_ISEN_P")
		)
		(pad "4" smd rect
			(at 2.70002 0 270)
			(size 0.4064 1.1176)
			(layers "F.Cu" "F.Mask" "F.Paste")
			(net "TP_P12V_AUX_CPU0_DIMM_ISEN_N")
		)
	)
	(footprint ""
		(layer "F.Cu")
		(at 155.459938 -118.132352 180)
		(property "Reference" "U206"
			(at -2.499106 -1.948434 0)
			(unlocked yes)
			(layer "F.SilkS")
			(effects
				(font
					(size 0.7874 0.5842)
					(thickness 0.1524)
				)
				(justify left)
			)
		)
		(property "Value" ""
			(at 0 0 180)
			(layer "F.Fab")
			(effects
				(font
					(size 1.27 1.27)
				)
			)
		)
		(duplicate_pad_numbers_are_jumpers no)
		(fp_line
			(start 2.046478 1.450086)
			(end 2.046478 -1.450086)
			(stroke
				(width 0.1524)
				(type default)
			)
			(layer "F.SilkS")
		)
		(fp_line
			(start 2.046478 -1.450086)
			(end 0.484886 -1.450086)
			(stroke
				(width 0.1524)
				(type default)
			)
			(layer "F.SilkS")
		)
		(fp_line
			(start 0.484886 -1.450086)
			(end 0 -0.762)
			(stroke
				(width 0.1524)
				(type default)
			)
			(layer "F.SilkS")
		)
		(fp_line
			(start 0 -0.762)
			(end -0.484886 -1.450086)
			(stroke
				(width 0.1524)
				(type default)
			)
			(layer "F.SilkS")
		)
		(fp_line
			(start -0.484886 -1.450086)
			(end -2.046478 -1.450086)
			(stroke
				(width 0.1524)
				(type default)
			)
			(layer "F.SilkS")
		)
		(fp_line
			(start -2.046478 1.450086)
			(end 2.046478 1.450086)
			(stroke
				(width 0.1524)
				(type default)
			)
			(layer "F.SilkS")
		)
		(fp_line
			(start -2.046478 -1.450086)
			(end -2.046478 1.450086)
			(stroke
				(width 0.1524)
				(type default)
			)
			(layer "F.SilkS")
		)
		(fp_poly
			(pts
				(xy -3.021076 -0.973836) (xy -4.037076 -0.465836) (xy -4.037076 -1.481836)
			)
			(stroke
				(width 0)
				(type default)
			)
			(fill yes)
			(layer "F.SilkS")
		)
		(fp_line
			(start 0.87503 1.450086)
			(end 0.87503 -1.450086)
			(stroke
				(width 0.1)
				(type default)
			)
			(layer "F.Fab")
		)
		(fp_line
			(start 0.87503 -1.450086)
			(end -0.87503 -1.450086)
			(stroke
				(width 0.1)
				(type default)
			)
			(layer "F.Fab")
		)
		(fp_line
			(start -0.87503 1.450086)
			(end 0.87503 1.450086)
			(stroke
				(width 0.1)
				(type default)
			)
			(layer "F.Fab")
		)
		(fp_line
			(start -0.87503 -1.450086)
			(end -0.87503 1.450086)
			(stroke
				(width 0.1)
				(type default)
			)
			(layer "F.Fab")
		)
		(fp_poly
			(pts
				(xy -3.2512 -0.44196) (xy -3.2512 -1.45796) (xy -2.2352 -0.94996)
			)
			(stroke
				(width 0)
				(type default)
			)
			(fill yes)
			(layer "F.Fab")
		)
		(pad "1" smd rect
			(at -1.309878 -0.94996 270)
			(size 0.635 1.2192)
			(layers "F.Cu" "F.Mask" "F.Paste")
			(net "FM_UV_ADR_TRIGGER_N")
		)
		(pad "2" smd rect
			(at -1.309878 0 270)
			(size 0.635 1.2192)
			(layers "F.Cu" "F.Mask" "F.Paste")
			(net "GND")
		)
		(pad "3" smd rect
			(at -1.309878 0.94996 270)
			(size 0.635 1.2192)
			(layers "F.Cu" "F.Mask" "F.Paste")
			(net "A_P12V_STBY_ADR_TRIGGER")
		)
		(pad "4" smd rect
			(at 1.309878 0.94996 270)
			(size 0.635 1.2192)
			(layers "F.Cu" "F.Mask" "F.Paste")
			(net "A_P12V_STBY_FP_TRIGGER")
		)
		(pad "5" smd rect
			(at 1.309878 0 270)
			(size 0.635 1.2192)
			(layers "F.Cu" "F.Mask" "F.Paste")
			(net "U206_VS")
		)
		(pad "6" smd rect
			(at 1.309878 -0.94996 270)
			(size 0.635 1.2192)
			(layers "F.Cu" "F.Mask" "F.Paste")
			(net "A_P12V_STBY_FPH_GATE")
		)
	)
	(footprint ""
		(layer "F.Cu")
		(at 358.389936 -392.48588 180)
		(property "Reference" "R1003"
			(at 0 0 180)
			(layer "F.SilkS")
			(hide yes)
			(effects
				(font
					(size 1.27 1.27)
				)
			)
		)
		(property "Value" ""
			(at 0 0 180)
			(layer "F.Fab")
			(effects
				(font
					(size 1.27 1.27)
				)
			)
		)
		(duplicate_pad_numbers_are_jumpers no)
		(fp_line
			(start 0.7874 0.4064)
			(end -0.7874 0.4064)
			(stroke
				(width 0.1524)
				(type default)
			)
			(layer "F.SilkS")
		)
		(fp_line
			(start 0.7874 -0.4064)
			(end 0.7874 0.4064)
			(stroke
				(width 0.1524)
				(type default)
			)
			(layer "F.SilkS")
		)
		(fp_line
			(start -0.7874 0.4064)
			(end -0.7874 -0.4064)
			(stroke
				(width 0.1524)
				(type default)
			)
			(layer "F.SilkS")
		)
		(fp_line
			(start -0.7874 -0.4064)
			(end 0.7874 -0.4064)
			(stroke
				(width 0.1524)
				(type default)
			)
			(layer "F.SilkS")
		)
		(fp_line
			(start 0.67945 0.3048)
			(end 0.120396 0.3048)
			(stroke
				(width 0.1)
				(type default)
			)
			(layer "F.Fab")
		)
		(fp_line
			(start 0.67945 -0.3048)
			(end 0.67945 0.3048)
			(stroke
				(width 0.1)
				(type default)
			)
			(layer "F.Fab")
		)
		(fp_line
			(start 0.12065 -0.2794)
			(end 0.12065 -0.3048)
			(stroke
				(width 0.1)
				(type default)
			)
			(layer "F.Fab")
		)
		(fp_line
			(start 0.12065 -0.3048)
			(end 0.67945 -0.3048)
			(stroke
				(width 0.1)
				(type default)
			)
			(layer "F.Fab")
		)
		(fp_line
			(start 0.120396 0.3048)
			(end 0.120396 0.2794)
			(stroke
				(width 0.1)
				(type default)
			)
			(layer "F.Fab")
		)
		(fp_line
			(start 0.120396 0.2794)
			(end -0.12065 0.2794)
			(stroke
				(width 0.1)
				(type default)
			)
			(layer "F.Fab")
		)
		(fp_line
			(start -0.12065 0.3048)
			(end -0.67945 0.3048)
			(stroke
				(width 0.1)
				(type default)
			)
			(layer "F.Fab")
		)
		(fp_line
			(start -0.12065 0.2794)
			(end -0.12065 0.3048)
			(stroke
				(width 0.1)
				(type default)
			)
			(layer "F.Fab")
		)
		(fp_line
			(start -0.12065 -0.2794)
			(end 0.12065 -0.2794)
			(stroke
				(width 0.1)
				(type default)
			)
			(layer "F.Fab")
		)
		(fp_line
			(start -0.12065 -0.305054)
			(end -0.12065 -0.2794)
			(stroke
				(width 0.1)
				(type default)
			)
			(layer "F.Fab")
		)
		(fp_line
			(start -0.67945 0.3048)
			(end -0.67945 -0.305054)
			(stroke
				(width 0.1)
				(type default)
			)
			(layer "F.Fab")
		)
		(fp_line
			(start -0.67945 -0.305054)
			(end -0.12065 -0.305054)
			(stroke
				(width 0.1)
				(type default)
			)
			(layer "F.Fab")
		)
		(pad "1" smd rect
			(at -0.40005 0)
			(size 0.4572 0.508)
			(layers "F.Cu" "F.Mask" "F.Paste")
			(net "P1V8_CPU0_RT1_1A_1D")
		)
		(pad "2" smd rect
			(at 0.40005 0)
			(size 0.4572 0.508)
			(layers "F.Cu" "F.Mask" "F.Paste")
			(net "P1V8_CPU0_RT1_1A")
		)
	)
	(footprint ""
		(layer "F.Cu")
		(at 386.184902 -416.899344 -90)
		(property "Reference" "C6576"
			(at 0 0 270)
			(layer "F.SilkS")
			(hide yes)
			(effects
				(font
					(size 1.27 1.27)
				)
			)
		)
		(property "Value" ""
			(at 0 0 270)
			(layer "F.Fab")
			(effects
				(font
					(size 1.27 1.27)
				)
			)
		)
		(duplicate_pad_numbers_are_jumpers no)
		(fp_line
			(start -0.299974 0.150114)
			(end -0.299974 -0.150114)
			(stroke
				(width 0.1)
				(type default)
			)
			(layer "F.Fab")
		)
		(fp_line
			(start 0.299974 0.150114)
			(end -0.299974 0.150114)
			(stroke
				(width 0.1)
				(type default)
			)
			(layer "F.Fab")
		)
		(fp_line
			(start -0.299974 -0.150114)
			(end 0.299974 -0.150114)
			(stroke
				(width 0.1)
				(type default)
			)
			(layer "F.Fab")
		)
		(fp_line
			(start 0.299974 -0.150114)
			(end 0.299974 0.150114)
			(stroke
				(width 0.1)
				(type default)
			)
			(layer "F.Fab")
		)
		(pad "1" smd rect
			(at -0.2667 0 270)
			(size 0.3048 0.381)
			(layers "F.Cu" "F.Mask" "F.Paste")
			(net "P5E_CPU0_P2_TX_BUF_C_DN<5>")
		)
		(pad "2" smd rect
			(at 0.2667 0 270)
			(size 0.3048 0.381)
			(layers "F.Cu" "F.Mask" "F.Paste")
			(net "P5E_CPU0_P2_TX_BUF_DN<5>")
		)
	)
)
